(kicad_pcb
	(version 20260206)
	(generator "pcbnew")
	(generator_version "10.0")
	(general
		(thickness 1.6)
		(legacy_teardrops no)
	)
	(paper "A4")
	(title_block
		(title "01162023_DA0F0TEBIF0_F0T_Expander_BD_F_brd_V02_OCP.brd")
		(comment 1 "Grand Teton / footprints 6556-6563 of 9728")
	)
	(layers
		(0 "F.Cu" signal "TOP")
		(4 "In1.Cu" signal "GND")
		(6 "In2.Cu" signal "VCC")
		(8 "In3.Cu" signal "VCC1")
		(10 "In4.Cu" signal "GND1")
		(12 "In5.Cu" signal "IN1")
		(14 "In6.Cu" signal "GND2")
		(16 "In7.Cu" signal "IN2")
		(18 "In8.Cu" signal "GND3")
		(20 "In9.Cu" signal "IN3")
		(22 "In10.Cu" signal "GND4")
		(24 "In11.Cu" signal "IN4")
		(26 "In12.Cu" signal "GND5")
		(28 "In13.Cu" signal "IN5")
		(30 "In14.Cu" signal "GND6")
		(32 "In15.Cu" signal "IN6")
		(34 "In16.Cu" signal "GND7")
		(2 "B.Cu" signal "BOTTOM")
		(9 "F.Adhes" user "F.Adhesive")
		(11 "B.Adhes" user "B.Adhesive")
		(13 "F.Paste" user "Package Geometry/Pastemask Top")
		(15 "B.Paste" user "Package Geometry/Pastemask Bottom")
		(5 "F.SilkS" user "Ref Des/Silkscreen Top")
		(7 "B.SilkS" user "Ref Des/Silkscreen Bottom")
		(1 "F.Mask" user "Board Geometry/Soldermask Top")
		(3 "B.Mask" user "Board Geometry/Soldermask Bottom")
		(17 "Dwgs.User" user "User.Drawings")
		(19 "Cmts.User" user "User.Comments")
		(21 "Eco1.User" user "User.Eco1")
		(23 "Eco2.User" user "User.Eco2")
		(25 "Edge.Cuts" user "Board Geometry/Outline")
		(27 "Margin" user)
		(31 "F.CrtYd" user "Package Geometry/Place Bound Top")
		(29 "B.CrtYd" user "Package Geometry/Place Bound Bottom")
		(35 "F.Fab" user "Ref Des/Assembly Top")
		(33 "B.Fab" user "Ref Des/Assembly Bottom")
	)
	(footprint ""
		(layer "F.Cu")
		(at 439.469022 -123.067318 90)
		(property "Reference" "PC491"
			(at 0 0 90)
			(layer "F.SilkS")
			(hide yes)
			(effects
				(font
					(size 1.27 1.27)
				)
			)
		)
		(property "Value" ""
			(at 0 0 90)
			(layer "F.Fab")
			(effects
				(font
					(size 1.27 1.27)
				)
			)
		)
		(duplicate_pad_numbers_are_jumpers no)
		(fp_line
			(start 1.524 -0.762)
			(end 1.524 0.762)
			(stroke
				(width 0.1524)
				(type default)
			)
			(layer "F.SilkS")
		)
		(fp_line
			(start -1.524 -0.762)
			(end 1.524 -0.762)
			(stroke
				(width 0.1524)
				(type default)
			)
			(layer "F.SilkS")
		)
		(fp_line
			(start 1.524 0.762)
			(end -1.524 0.762)
			(stroke
				(width 0.1524)
				(type default)
			)
			(layer "F.SilkS")
		)
		(fp_line
			(start -1.524 0.762)
			(end -1.524 -0.762)
			(stroke
				(width 0.1524)
				(type default)
			)
			(layer "F.SilkS")
		)
		(fp_line
			(start 1.1049 -0.724916)
			(end -1.1049 -0.724916)
			(stroke
				(width 0.1)
				(type default)
			)
			(layer "F.Fab")
		)
		(fp_line
			(start -1.1049 -0.724916)
			(end -1.1049 0.724916)
			(stroke
				(width 0.1)
				(type default)
			)
			(layer "F.Fab")
		)
		(fp_line
			(start 1.1049 0.724916)
			(end 1.1049 -0.724916)
			(stroke
				(width 0.1)
				(type default)
			)
			(layer "F.Fab")
		)
		(fp_line
			(start -1.1049 0.724916)
			(end 1.1049 0.724916)
			(stroke
				(width 0.1)
				(type default)
			)
			(layer "F.Fab")
		)
		(pad "1" smd rect
			(at -0.889 0 270)
			(size 1.016 1.27)
			(layers "F.Cu" "F.Mask" "F.Paste")
			(net "P3V3_NIC7")
		)
		(pad "2" smd rect
			(at 0.889 0 270)
			(size 1.016 1.27)
			(layers "F.Cu" "F.Mask" "F.Paste")
			(net "GND")
		)
	)
	(footprint ""
		(layer "F.Cu")
		(at 35.3695 -256.888234 -90)
		(property "Reference" "R4563"
			(at 0 0 270)
			(layer "F.SilkS")
			(hide yes)
			(effects
				(font
					(size 1.27 1.27)
				)
			)
		)
		(property "Value" ""
			(at 0 0 270)
			(layer "F.Fab")
			(effects
				(font
					(size 1.27 1.27)
				)
			)
		)
		(duplicate_pad_numbers_are_jumpers no)
		(fp_line
			(start -0.7874 0.4064)
			(end -0.7874 -0.4064)
			(stroke
				(width 0.1524)
				(type default)
			)
			(layer "F.SilkS")
		)
		(fp_line
			(start 0.7874 0.4064)
			(end -0.7874 0.4064)
			(stroke
				(width 0.1524)
				(type default)
			)
			(layer "F.SilkS")
		)
		(fp_line
			(start -0.7874 -0.4064)
			(end 0.7874 -0.4064)
			(stroke
				(width 0.1524)
				(type default)
			)
			(layer "F.SilkS")
		)
		(fp_line
			(start 0.7874 -0.4064)
			(end 0.7874 0.4064)
			(stroke
				(width 0.1524)
				(type default)
			)
			(layer "F.SilkS")
		)
		(fp_line
			(start -0.67945 0.3048)
			(end -0.67945 -0.305054)
			(stroke
				(width 0.1)
				(type default)
			)
			(layer "F.Fab")
		)
		(fp_line
			(start -0.12065 0.3048)
			(end -0.67945 0.3048)
			(stroke
				(width 0.1)
				(type default)
			)
			(layer "F.Fab")
		)
		(fp_line
			(start 0.120396 0.3048)
			(end 0.120396 0.2794)
			(stroke
				(width 0.1)
				(type default)
			)
			(layer "F.Fab")
		)
		(fp_line
			(start 0.67945 0.3048)
			(end 0.120396 0.3048)
			(stroke
				(width 0.1)
				(type default)
			)
			(layer "F.Fab")
		)
		(fp_line
			(start -0.12065 0.2794)
			(end -0.12065 0.3048)
			(stroke
				(width 0.1)
				(type default)
			)
			(layer "F.Fab")
		)
		(fp_line
			(start 0.120396 0.2794)
			(end -0.12065 0.2794)
			(stroke
				(width 0.1)
				(type default)
			)
			(layer "F.Fab")
		)
		(fp_line
			(start -0.12065 -0.2794)
			(end 0.12065 -0.2794)
			(stroke
				(width 0.1)
				(type default)
			)
			(layer "F.Fab")
		)
		(fp_line
			(start 0.12065 -0.2794)
			(end 0.12065 -0.3048)
			(stroke
				(width 0.1)
				(type default)
			)
			(layer "F.Fab")
		)
		(fp_line
			(start 0.12065 -0.3048)
			(end 0.67945 -0.3048)
			(stroke
				(width 0.1)
				(type default)
			)
			(layer "F.Fab")
		)
		(fp_line
			(start 0.67945 -0.3048)
			(end 0.67945 0.3048)
			(stroke
				(width 0.1)
				(type default)
			)
			(layer "F.Fab")
		)
		(fp_line
			(start -0.67945 -0.305054)
			(end -0.12065 -0.305054)
			(stroke
				(width 0.1)
				(type default)
			)
			(layer "F.Fab")
		)
		(fp_line
			(start -0.12065 -0.305054)
			(end -0.12065 -0.2794)
			(stroke
				(width 0.1)
				(type default)
			)
			(layer "F.Fab")
		)
		(pad "1" smd circle
			(at -0.40005 0 270)
			(size 0 0)
			(layers "F.Cu" "F.Mask" "F.Paste")
			(net "PCEPLL5_VDDA18_PEX0")
		)
		(pad "2" smd circle
			(at 0.40005 0 270)
			(size 0 0)
			(layers "F.Cu" "F.Mask" "F.Paste")
			(net "PCEPLL5_VDDA18_PEX0_R")
		)
	)
	(footprint ""
		(layer "F.Cu")
		(at 98.27387 -72.766682 90)
		(property "Reference" "PR6911"
			(at 0 0 90)
			(layer "F.SilkS")
			(hide yes)
			(effects
				(font
					(size 1.27 1.27)
				)
			)
		)
		(property "Value" ""
			(at 0 0 90)
			(layer "F.Fab")
			(effects
				(font
					(size 1.27 1.27)
				)
			)
		)
		(duplicate_pad_numbers_are_jumpers no)
		(fp_line
			(start 0.7874 -0.4064)
			(end 0.7874 0.4064)
			(stroke
				(width 0.1524)
				(type default)
			)
			(layer "F.SilkS")
		)
		(fp_line
			(start -0.7874 -0.4064)
			(end 0.7874 -0.4064)
			(stroke
				(width 0.1524)
				(type default)
			)
			(layer "F.SilkS")
		)
		(fp_line
			(start 0.7874 0.4064)
			(end -0.7874 0.4064)
			(stroke
				(width 0.1524)
				(type default)
			)
			(layer "F.SilkS")
		)
		(fp_line
			(start -0.7874 0.4064)
			(end -0.7874 -0.4064)
			(stroke
				(width 0.1524)
				(type default)
			)
			(layer "F.SilkS")
		)
		(fp_line
			(start -0.12065 -0.305054)
			(end -0.12065 -0.2794)
			(stroke
				(width 0.1)
				(type default)
			)
			(layer "F.Fab")
		)
		(fp_line
			(start -0.67945 -0.305054)
			(end -0.12065 -0.305054)
			(stroke
				(width 0.1)
				(type default)
			)
			(layer "F.Fab")
		)
		(fp_line
			(start 0.67945 -0.3048)
			(end 0.67945 0.3048)
			(stroke
				(width 0.1)
				(type default)
			)
			(layer "F.Fab")
		)
		(fp_line
			(start 0.12065 -0.3048)
			(end 0.67945 -0.3048)
			(stroke
				(width 0.1)
				(type default)
			)
			(layer "F.Fab")
		)
		(fp_line
			(start 0.12065 -0.2794)
			(end 0.12065 -0.3048)
			(stroke
				(width 0.1)
				(type default)
			)
			(layer "F.Fab")
		)
		(fp_line
			(start -0.12065 -0.2794)
			(end 0.12065 -0.2794)
			(stroke
				(width 0.1)
				(type default)
			)
			(layer "F.Fab")
		)
		(fp_line
			(start 0.120396 0.2794)
			(end -0.12065 0.2794)
			(stroke
				(width 0.1)
				(type default)
			)
			(layer "F.Fab")
		)
		(fp_line
			(start -0.12065 0.2794)
			(end -0.12065 0.3048)
			(stroke
				(width 0.1)
				(type default)
			)
			(layer "F.Fab")
		)
		(fp_line
			(start 0.67945 0.3048)
			(end 0.120396 0.3048)
			(stroke
				(width 0.1)
				(type default)
			)
			(layer "F.Fab")
		)
		(fp_line
			(start 0.120396 0.3048)
			(end 0.120396 0.2794)
			(stroke
				(width 0.1)
				(type default)
			)
			(layer "F.Fab")
		)
		(fp_line
			(start -0.12065 0.3048)
			(end -0.67945 0.3048)
			(stroke
				(width 0.1)
				(type default)
			)
			(layer "F.Fab")
		)
		(fp_line
			(start -0.67945 0.3048)
			(end -0.67945 -0.305054)
			(stroke
				(width 0.1)
				(type default)
			)
			(layer "F.Fab")
		)
		(pad "1" smd circle
			(at -0.40005 0 90)
			(size 0 0)
			(layers "F.Cu" "F.Mask" "F.Paste")
			(net "P12V_SSD3_CO_MODE")
		)
		(pad "2" smd circle
			(at 0.40005 0 90)
			(size 0 0)
			(layers "F.Cu" "F.Mask" "F.Paste")
			(net "GND")
		)
	)
	(footprint ""
		(layer "F.Cu")
		(at 52.267866 -55.083456)
		(property "Reference" "PC421"
			(at 0 0 0)
			(layer "F.SilkS")
			(hide yes)
			(effects
				(font
					(size 1.27 1.27)
				)
			)
		)
		(property "Value" ""
			(at 0 0 0)
			(layer "F.Fab")
			(effects
				(font
					(size 1.27 1.27)
				)
			)
		)
		(duplicate_pad_numbers_are_jumpers no)
		(fp_line
			(start -0.7874 -0.4064)
			(end 0.7874 -0.4064)
			(stroke
				(width 0.1524)
				(type default)
			)
			(layer "F.SilkS")
		)
		(fp_line
			(start -0.7874 0.4064)
			(end -0.7874 -0.4064)
			(stroke
				(width 0.1524)
				(type default)
			)
			(layer "F.SilkS")
		)
		(fp_line
			(start 0.7874 -0.4064)
			(end 0.7874 0.4064)
			(stroke
				(width 0.1524)
				(type default)
			)
			(layer "F.SilkS")
		)
		(fp_line
			(start 0.7874 0.4064)
			(end -0.7874 0.4064)
			(stroke
				(width 0.1524)
				(type default)
			)
			(layer "F.SilkS")
		)
		(fp_line
			(start -0.67945 -0.305054)
			(end -0.12065 -0.305054)
			(stroke
				(width 0.1)
				(type default)
			)
			(layer "F.Fab")
		)
		(fp_line
			(start -0.67945 0.3048)
			(end -0.67945 -0.305054)
			(stroke
				(width 0.1)
				(type default)
			)
			(layer "F.Fab")
		)
		(fp_line
			(start -0.12065 -0.305054)
			(end -0.12065 -0.2794)
			(stroke
				(width 0.1)
				(type default)
			)
			(layer "F.Fab")
		)
		(fp_line
			(start -0.12065 -0.2794)
			(end 0.12065 -0.2794)
			(stroke
				(width 0.1)
				(type default)
			)
			(layer "F.Fab")
		)
		(fp_line
			(start -0.12065 0.2794)
			(end -0.12065 0.3048)
			(stroke
				(width 0.1)
				(type default)
			)
			(layer "F.Fab")
		)
		(fp_line
			(start -0.12065 0.3048)
			(end -0.67945 0.3048)
			(stroke
				(width 0.1)
				(type default)
			)
			(layer "F.Fab")
		)
		(fp_line
			(start 0.120396 0.2794)
			(end -0.12065 0.2794)
			(stroke
				(width 0.1)
				(type default)
			)
			(layer "F.Fab")
		)
		(fp_line
			(start 0.120396 0.3048)
			(end 0.120396 0.2794)
			(stroke
				(width 0.1)
				(type default)
			)
			(layer "F.Fab")
		)
		(fp_line
			(start 0.12065 -0.3048)
			(end 0.67945 -0.3048)
			(stroke
				(width 0.1)
				(type default)
			)
			(layer "F.Fab")
		)
		(fp_line
			(start 0.12065 -0.2794)
			(end 0.12065 -0.3048)
			(stroke
				(width 0.1)
				(type default)
			)
			(layer "F.Fab")
		)
		(fp_line
			(start 0.67945 -0.3048)
			(end 0.67945 0.3048)
			(stroke
				(width 0.1)
				(type default)
			)
			(layer "F.Fab")
		)
		(fp_line
			(start 0.67945 0.3048)
			(end 0.120396 0.3048)
			(stroke
				(width 0.1)
				(type default)
			)
			(layer "F.Fab")
		)
		(pad "1" smd circle
			(at -0.40005 0)
			(size 0 0)
			(layers "F.Cu" "F.Mask" "F.Paste")
			(net "P5V_AUX")
		)
		(pad "2" smd circle
			(at 0.40005 0)
			(size 0 0)
			(layers "F.Cu" "F.Mask" "F.Paste")
			(net "GND")
		)
	)
	(footprint ""
		(layer "F.Cu")
		(at 152.738328 -120.113298)
		(property "Reference" "C259"
			(at 0 0 0)
			(layer "F.SilkS")
			(hide yes)
			(effects
				(font
					(size 1.27 1.27)
				)
			)
		)
		(property "Value" ""
			(at 0 0 0)
			(layer "F.Fab")
			(effects
				(font
					(size 1.27 1.27)
				)
			)
		)
		(duplicate_pad_numbers_are_jumpers no)
		(fp_line
			(start -0.299974 -0.150114)
			(end 0.299974 -0.150114)
			(stroke
				(width 0.1)
				(type default)
			)
			(layer "F.Fab")
		)
		(fp_line
			(start -0.299974 0.150114)
			(end -0.299974 -0.150114)
			(stroke
				(width 0.1)
				(type default)
			)
			(layer "F.Fab")
		)
		(fp_line
			(start 0.299974 -0.150114)
			(end 0.299974 0.150114)
			(stroke
				(width 0.1)
				(type default)
			)
			(layer "F.Fab")
		)
		(fp_line
			(start 0.299974 0.150114)
			(end -0.299974 0.150114)
			(stroke
				(width 0.1)
				(type default)
			)
			(layer "F.Fab")
		)
		(pad "1" smd rect
			(at -0.2667 0)
			(size 0.3048 0.381)
			(layers "F.Cu" "F.Mask" "F.Paste")
			(net "P5E_PEX1_STN1_TX_DN<24>")
		)
		(pad "2" smd rect
			(at 0.2667 0)
			(size 0.3048 0.381)
			(layers "F.Cu" "F.Mask" "F.Paste")
			(net "P5E_PEX1_STN1_TX_C_DN<24>")
		)
	)
	(footprint ""
		(layer "F.Cu")
		(at 411.77083 -138.864848)
		(property "Reference" "R397"
			(at 0 0 0)
			(layer "F.SilkS")
			(hide yes)
			(effects
				(font
					(size 1.27 1.27)
				)
			)
		)
		(property "Value" ""
			(at 0 0 0)
			(layer "F.Fab")
			(effects
				(font
					(size 1.27 1.27)
				)
			)
		)
		(duplicate_pad_numbers_are_jumpers no)
		(fp_line
			(start -0.7874 -0.4064)
			(end 0.7874 -0.4064)
			(stroke
				(width 0.1524)
				(type default)
			)
			(layer "F.SilkS")
		)
		(fp_line
			(start -0.7874 0.4064)
			(end -0.7874 -0.4064)
			(stroke
				(width 0.1524)
				(type default)
			)
			(layer "F.SilkS")
		)
		(fp_line
			(start 0.7874 -0.4064)
			(end 0.7874 0.4064)
			(stroke
				(width 0.1524)
				(type default)
			)
			(layer "F.SilkS")
		)
		(fp_line
			(start 0.7874 0.4064)
			(end -0.7874 0.4064)
			(stroke
				(width 0.1524)
				(type default)
			)
			(layer "F.SilkS")
		)
		(fp_line
			(start -0.67945 -0.305054)
			(end -0.12065 -0.305054)
			(stroke
				(width 0.1)
				(type default)
			)
			(layer "F.Fab")
		)
		(fp_line
			(start -0.67945 0.3048)
			(end -0.67945 -0.305054)
			(stroke
				(width 0.1)
				(type default)
			)
			(layer "F.Fab")
		)
		(fp_line
			(start -0.12065 -0.305054)
			(end -0.12065 -0.2794)
			(stroke
				(width 0.1)
				(type default)
			)
			(layer "F.Fab")
		)
		(fp_line
			(start -0.12065 -0.2794)
			(end 0.12065 -0.2794)
			(stroke
				(width 0.1)
				(type default)
			)
			(layer "F.Fab")
		)
		(fp_line
			(start -0.12065 0.2794)
			(end -0.12065 0.3048)
			(stroke
				(width 0.1)
				(type default)
			)
			(layer "F.Fab")
		)
		(fp_line
			(start -0.12065 0.3048)
			(end -0.67945 0.3048)
			(stroke
				(width 0.1)
				(type default)
			)
			(layer "F.Fab")
		)
		(fp_line
			(start 0.120396 0.2794)
			(end -0.12065 0.2794)
			(stroke
				(width 0.1)
				(type default)
			)
			(layer "F.Fab")
		)
		(fp_line
			(start 0.120396 0.3048)
			(end 0.120396 0.2794)
			(stroke
				(width 0.1)
				(type default)
			)
			(layer "F.Fab")
		)
		(fp_line
			(start 0.12065 -0.3048)
			(end 0.67945 -0.3048)
			(stroke
				(width 0.1)
				(type default)
			)
			(layer "F.Fab")
		)
		(fp_line
			(start 0.12065 -0.2794)
			(end 0.12065 -0.3048)
			(stroke
				(width 0.1)
				(type default)
			)
			(layer "F.Fab")
		)
		(fp_line
			(start 0.67945 -0.3048)
			(end 0.67945 0.3048)
			(stroke
				(width 0.1)
				(type default)
			)
			(layer "F.Fab")
		)
		(fp_line
			(start 0.67945 0.3048)
			(end 0.120396 0.3048)
			(stroke
				(width 0.1)
				(type default)
			)
			(layer "F.Fab")
		)
		(pad "1" smd circle
			(at -0.40005 0)
			(size 0 0)
			(layers "F.Cu" "F.Mask" "F.Paste")
			(net "PRSNT_NIC7_N")
		)
		(pad "2" smd circle
			(at 0.40005 0)
			(size 0 0)
			(layers "F.Cu" "F.Mask" "F.Paste")
			(net "PRSNTB1_NIC7_N")
		)
	)
	(footprint ""
		(layer "F.Cu")
		(at 312.21934 -150.70455 180)
		(property "Reference" "C429"
			(at 0 0 180)
			(layer "F.SilkS")
			(hide yes)
			(effects
				(font
					(size 1.27 1.27)
				)
			)
		)
		(property "Value" ""
			(at 0 0 180)
			(layer "F.Fab")
			(effects
				(font
					(size 1.27 1.27)
				)
			)
		)
		(duplicate_pad_numbers_are_jumpers no)
		(fp_line
			(start 0.299974 0.150114)
			(end -0.299974 0.150114)
			(stroke
				(width 0.1)
				(type default)
			)
			(layer "F.Fab")
		)
		(fp_line
			(start 0.299974 -0.150114)
			(end 0.299974 0.150114)
			(stroke
				(width 0.1)
				(type default)
			)
			(layer "F.Fab")
		)
		(fp_line
			(start -0.299974 0.150114)
			(end -0.299974 -0.150114)
			(stroke
				(width 0.1)
				(type default)
			)
			(layer "F.Fab")
		)
		(fp_line
			(start -0.299974 -0.150114)
			(end 0.299974 -0.150114)
			(stroke
				(width 0.1)
				(type default)
			)
			(layer "F.Fab")
		)
		(pad "1" smd rect
			(at -0.2667 0 180)
			(size 0.3048 0.381)
			(layers "F.Cu" "F.Mask" "F.Paste")
			(net "P5E_PEX2_STN0_TX_DN<12>")
		)
		(pad "2" smd rect
			(at 0.2667 0 180)
			(size 0.3048 0.381)
			(layers "F.Cu" "F.Mask" "F.Paste")
			(net "P5E_PEX2_STN0_TX_C_DN<12>")
		)
	)
	(footprint ""
		(layer "F.Cu")
		(at 189.047374 -20.35556)
		(property "Reference" "C3919"
			(at 0 0 0)
			(layer "F.SilkS")
			(hide yes)
			(effects
				(font
					(size 1.27 1.27)
				)
			)
		)
		(property "Value" ""
			(at 0 0 0)
			(layer "F.Fab")
			(effects
				(font
					(size 1.27 1.27)
				)
			)
		)
		(duplicate_pad_numbers_are_jumpers no)
		(fp_line
			(start -0.7874 -0.4064)
			(end 0.7874 -0.4064)
			(stroke
				(width 0.1524)
				(type default)
			)
			(layer "F.SilkS")
		)
		(fp_line
			(start -0.7874 0.4064)
			(end -0.7874 -0.4064)
			(stroke
				(width 0.1524)
				(type default)
			)
			(layer "F.SilkS")
		)
		(fp_line
			(start 0.7874 -0.4064)
			(end 0.7874 0.4064)
			(stroke
				(width 0.1524)
				(type default)
			)
			(layer "F.SilkS")
		)
		(fp_line
			(start 0.7874 0.4064)
			(end -0.7874 0.4064)
			(stroke
				(width 0.1524)
				(type default)
			)
			(layer "F.SilkS")
		)
		(fp_line
			(start -0.67945 -0.305054)
			(end -0.12065 -0.305054)
			(stroke
				(width 0.1)
				(type default)
			)
			(layer "F.Fab")
		)
		(fp_line
			(start -0.67945 0.3048)
			(end -0.67945 -0.305054)
			(stroke
				(width 0.1)
				(type default)
			)
			(layer "F.Fab")
		)
		(fp_line
			(start -0.12065 -0.305054)
			(end -0.12065 -0.2794)
			(stroke
				(width 0.1)
				(type default)
			)
			(layer "F.Fab")
		)
		(fp_line
			(start -0.12065 -0.2794)
			(end 0.12065 -0.2794)
			(stroke
				(width 0.1)
				(type default)
			)
			(layer "F.Fab")
		)
		(fp_line
			(start -0.12065 0.2794)
			(end -0.12065 0.3048)
			(stroke
				(width 0.1)
				(type default)
			)
			(layer "F.Fab")
		)
		(fp_line
			(start -0.12065 0.3048)
			(end -0.67945 0.3048)
			(stroke
				(width 0.1)
				(type default)
			)
			(layer "F.Fab")
		)
		(fp_line
			(start 0.120396 0.2794)
			(end -0.12065 0.2794)
			(stroke
				(width 0.1)
				(type default)
			)
			(layer "F.Fab")
		)
		(fp_line
			(start 0.120396 0.3048)
			(end 0.120396 0.2794)
			(stroke
				(width 0.1)
				(type default)
			)
			(layer "F.Fab")
		)
		(fp_line
			(start 0.12065 -0.3048)
			(end 0.67945 -0.3048)
			(stroke
				(width 0.1)
				(type default)
			)
			(layer "F.Fab")
		)
		(fp_line
			(start 0.12065 -0.2794)
			(end 0.12065 -0.3048)
			(stroke
				(width 0.1)
				(type default)
			)
			(layer "F.Fab")
		)
		(fp_line
			(start 0.67945 -0.3048)
			(end 0.67945 0.3048)
			(stroke
				(width 0.1)
				(type default)
			)
			(layer "F.Fab")
		)
		(fp_line
			(start 0.67945 0.3048)
			(end 0.120396 0.3048)
			(stroke
				(width 0.1)
				(type default)
			)
			(layer "F.Fab")
		)
		(pad "1" smd circle
			(at -0.40005 0)
			(size 0 0)
			(layers "F.Cu" "F.Mask" "F.Paste")
			(net "P12V_SSD6")
		)
		(pad "2" smd circle
			(at 0.40005 0)
			(size 0 0)
			(layers "F.Cu" "F.Mask" "F.Paste")
			(net "GND")
		)
	)
)
